# T6G (Grand Teton) — schematic netlist excerpt (pin names and nets, part order shuffled) for the footprints in the layout excerpt that follows; sources: Cadence DE-HDL packaged netlist, KiCad conversion of 04192023_DAF0TMB3IC0_F0TG_MB_C_brd_V02_OCP.brd

PC486_2  Q_CAP  22UF 16V 20% X6S  pkg C0805  page 194 : A = SW_P12V_AUX_PVDDCR_CPU0_P0_FLT ; B = GND
PR231  Q_RES  10K 1% CHIP  pkg 0402LF  page 217 : A = PVDDCR_CPU1_P1_VMON ; B = GND
R1515  Q_RES  0 5% CHIP  pkg 0201LF  page 184 : A = SMB_MUX_RT_R1_SDA ; B = SMB_MUX_RT_R2_SDA

(kicad_pcb
	(version 20260206)
	(generator "pcbnew")
	(generator_version "10.0")
	(general
		(thickness 1.6)
		(legacy_teardrops no)
	)
	(paper "A4")
	(title_block
		(title "04192023_DAF0TMB3IC0_F0TG_MB_C_brd_V02_OCP.brd")
		(comment 1 "Grand Teton / footprints 5554-5556 of 8354")
	)
	(layers
		(0 "F.Cu" signal "TOP")
		(4 "In1.Cu" signal "GND")
		(6 "In2.Cu" signal "IN1")
		(8 "In3.Cu" signal "GND1")
		(10 "In4.Cu" signal "IN2")
		(12 "In5.Cu" signal "GND2")
		(14 "In6.Cu" signal "IN3")
		(16 "In7.Cu" signal "GND3")
		(18 "In8.Cu" signal "VCC")
		(20 "In9.Cu" signal "VCC1")
		(22 "In10.Cu" signal "GND4")
		(24 "In11.Cu" signal "IN4")
		(26 "In12.Cu" signal "GND5")
		(28 "In13.Cu" signal "IN5")
		(30 "In14.Cu" signal "GND6")
		(32 "In15.Cu" signal "IN6")
		(34 "In16.Cu" signal "GND7")
		(2 "B.Cu" signal "BOTTOM")
		(9 "F.Adhes" user "F.Adhesive")
		(11 "B.Adhes" user "B.Adhesive")
		(13 "F.Paste" user "Package Geometry/Pastemask Top")
		(15 "B.Paste" user "Package Geometry/Pastemask Bottom")
		(5 "F.SilkS" user "Ref Des/Silkscreen Top")
		(7 "B.SilkS" user "Ref Des/Silkscreen Bottom")
		(1 "F.Mask" user "Board Geometry/Soldermask Top")
		(3 "B.Mask" user "Board Geometry/Soldermask Bottom")
		(17 "Dwgs.User" user "User.Drawings")
		(19 "Cmts.User" user "User.Comments")
		(21 "Eco1.User" user "User.Eco1")
		(23 "Eco2.User" user "User.Eco2")
		(25 "Edge.Cuts" user "Board Geometry/Outline")
		(27 "Margin" user)
		(31 "F.CrtYd" user "Package Geometry/Place Bound Top")
		(29 "B.CrtYd" user "Package Geometry/Place Bound Bottom")
		(35 "F.Fab" user "Ref Des/Assembly Top")
		(33 "B.Fab" user "Ref Des/Assembly Bottom")
	)
	(footprint ""
		(layer "B.Cu")
		(at 245.7704 -331.2668 180)
		(property "Reference" "R1515"
			(at 0 0 0)
			(layer "B.SilkS")
			(hide yes)
			(effects
				(font
					(size 1.27 1.27)
				)
				(justify mirror)
			)
		)
		(property "Value" ""
			(at 0 0 0)
			(layer "B.Fab")
			(effects
				(font
					(size 1.27 1.27)
				)
				(justify mirror)
			)
		)
		(duplicate_pad_numbers_are_jumpers no)
		(fp_line
			(start 0.32512 0.175006)
			(end 0.32512 -0.175006)
			(stroke
				(width 0.1)
				(type default)
			)
			(layer "B.Fab")
		)
		(fp_line
			(start 0.32512 -0.175006)
			(end -0.32512 -0.175006)
			(stroke
				(width 0.1)
				(type default)
			)
			(layer "B.Fab")
		)
		(fp_line
			(start -0.32512 0.175006)
			(end 0.32512 0.175006)
			(stroke
				(width 0.1)
				(type default)
			)
			(layer "B.Fab")
		)
		(fp_line
			(start -0.32512 -0.175006)
			(end -0.32512 0.175006)
			(stroke
				(width 0.1)
				(type default)
			)
			(layer "B.Fab")
		)
		(pad "1" smd rect
			(at 0.2667 0)
			(size 0.3048 0.381)
			(layers "B.Cu" "B.Mask" "B.Paste")
			(net "SMB_MUX_RT_R1_SDA")
		)
		(pad "2" smd rect
			(at -0.2667 0 180)
			(size 0.3048 0.381)
			(layers "B.Cu" "B.Mask" "B.Paste")
			(net "SMB_MUX_RT_R2_SDA")
		)
	)
	(footprint ""
		(layer "B.Cu")
		(at 34.544 -362.966)
		(property "Reference" "PR231"
			(at 0 0 0)
			(layer "B.SilkS")
			(hide yes)
			(effects
				(font
					(size 1.27 1.27)
				)
				(justify mirror)
			)
		)
		(property "Value" ""
			(at 0 0 0)
			(layer "B.Fab")
			(effects
				(font
					(size 1.27 1.27)
				)
				(justify mirror)
			)
		)
		(duplicate_pad_numbers_are_jumpers no)
		(fp_line
			(start -0.7874 -0.4064)
			(end -0.7874 0.4064)
			(stroke
				(width 0.1524)
				(type default)
			)
			(layer "B.SilkS")
		)
		(fp_line
			(start -0.7874 0.4064)
			(end 0.7874 0.4064)
			(stroke
				(width 0.1524)
				(type default)
			)
			(layer "B.SilkS")
		)
		(fp_line
			(start 0.7874 -0.4064)
			(end -0.7874 -0.4064)
			(stroke
				(width 0.1524)
				(type default)
			)
			(layer "B.SilkS")
		)
		(fp_line
			(start 0.7874 0.4064)
			(end 0.7874 -0.4064)
			(stroke
				(width 0.1524)
				(type default)
			)
			(layer "B.SilkS")
		)
		(fp_line
			(start -0.67945 -0.3048)
			(end -0.67945 0.3048)
			(stroke
				(width 0.1)
				(type default)
			)
			(layer "B.Fab")
		)
		(fp_line
			(start -0.67945 0.3048)
			(end -0.120396 0.3048)
			(stroke
				(width 0.1)
				(type default)
			)
			(layer "B.Fab")
		)
		(fp_line
			(start -0.12065 -0.3048)
			(end -0.67945 -0.3048)
			(stroke
				(width 0.1)
				(type default)
			)
			(layer "B.Fab")
		)
		(fp_line
			(start -0.12065 -0.2794)
			(end -0.12065 -0.3048)
			(stroke
				(width 0.1)
				(type default)
			)
			(layer "B.Fab")
		)
		(fp_line
			(start -0.120396 0.2794)
			(end 0.12065 0.2794)
			(stroke
				(width 0.1)
				(type default)
			)
			(layer "B.Fab")
		)
		(fp_line
			(start -0.120396 0.3048)
			(end -0.120396 0.2794)
			(stroke
				(width 0.1)
				(type default)
			)
			(layer "B.Fab")
		)
		(fp_line
			(start 0.12065 -0.305054)
			(end 0.12065 -0.2794)
			(stroke
				(width 0.1)
				(type default)
			)
			(layer "B.Fab")
		)
		(fp_line
			(start 0.12065 -0.2794)
			(end -0.12065 -0.2794)
			(stroke
				(width 0.1)
				(type default)
			)
			(layer "B.Fab")
		)
		(fp_line
			(start 0.12065 0.2794)
			(end 0.12065 0.3048)
			(stroke
				(width 0.1)
				(type default)
			)
			(layer "B.Fab")
		)
		(fp_line
			(start 0.12065 0.3048)
			(end 0.67945 0.3048)
			(stroke
				(width 0.1)
				(type default)
			)
			(layer "B.Fab")
		)
		(fp_line
			(start 0.67945 -0.305054)
			(end 0.12065 -0.305054)
			(stroke
				(width 0.1)
				(type default)
			)
			(layer "B.Fab")
		)
		(fp_line
			(start 0.67945 0.3048)
			(end 0.67945 -0.305054)
			(stroke
				(width 0.1)
				(type default)
			)
			(layer "B.Fab")
		)
		(pad "1" smd circle
			(at 0.40005 0 180)
			(size 0 0)
			(layers "B.Cu" "B.Mask" "B.Paste")
			(net "PVDDCR_CPU1_P1_VMON")
		)
		(pad "2" smd circle
			(at -0.40005 0 180)
			(size 0 0)
			(layers "B.Cu" "B.Mask" "B.Paste")
			(net "GND")
		)
	)
	(footprint ""
		(layer "B.Cu")
		(at 369.425474 -182.676038 -90)
		(property "Reference" "PC486_2"
			(at 0 0 90)
			(layer "B.SilkS")
			(hide yes)
			(effects
				(font
					(size 1.27 1.27)
				)
				(justify mirror)
			)
		)
		(property "Value" ""
			(at 0 0 90)
			(layer "B.Fab")
			(effects
				(font
					(size 1.27 1.27)
				)
				(justify mirror)
			)
		)
		(duplicate_pad_numbers_are_jumpers no)
		(fp_line
			(start -1.524 0.762)
			(end 1.524 0.762)
			(stroke
				(width 0.1524)
				(type default)
			)
			(layer "B.SilkS")
		)
		(fp_line
			(start 1.524 0.762)
			(end 1.524 -0.762)
			(stroke
				(width 0.1524)
				(type default)
			)
			(layer "B.SilkS")
		)
		(fp_line
			(start -1.524 -0.762)
			(end -1.524 0.762)
			(stroke
				(width 0.1524)
				(type default)
			)
			(layer "B.SilkS")
		)
		(fp_line
			(start 1.524 -0.762)
			(end -1.524 -0.762)
			(stroke
				(width 0.1524)
				(type default)
			)
			(layer "B.SilkS")
		)
		(fp_line
			(start -1.1049 0.724916)
			(end -1.1049 -0.724916)
			(stroke
				(width 0.1)
				(type default)
			)
			(layer "B.Fab")
		)
		(fp_line
			(start 1.1049 0.724916)
			(end -1.1049 0.724916)
			(stroke
				(width 0.1)
				(type default)
			)
			(layer "B.Fab")
		)
		(fp_line
			(start -1.1049 -0.724916)
			(end 1.1049 -0.724916)
			(stroke
				(width 0.1)
				(type default)
			)
			(layer "B.Fab")
		)
		(fp_line
			(start 1.1049 -0.724916)
			(end 1.1049 0.724916)
			(stroke
				(width 0.1)
				(type default)
			)
			(layer "B.Fab")
		)
		(pad "1" smd rect
			(at 0.889 0 270)
			(size 1.016 1.27)
			(layers "B.Cu" "B.Mask" "B.Paste")
			(net "SW_P12V_AUX_PVDDCR_CPU0_P0_FLT")
		)
		(pad "2" smd rect
			(at -0.889 0 270)
			(size 1.016 1.27)
			(layers "B.Cu" "B.Mask" "B.Paste")
			(net "GND")
		)
	)
)
